FILE_TYPE = CONNECTIVITY;
{Allegro Design Entry HDL 17.2-2016 S081 (4005846) 1/11/2022}
"PAGE_NUMBER" = 238;
0"NC";
END.
